(kicad_pcb
	(version 20241229)
	(generator "pcbnew")
	(generator_version "9.0")
	(general
		(thickness 1.599998)
		(legacy_teardrops no)
	)
	(paper "A4")
	(title_block
		(date "2023-02-12")
		(rev "1.1.5")
		(comment 9 "footprints 290-296 of 473")
	)
	(layers
		(0 "F.Cu" signal)
		(4 "In1.Cu" power "In1.GND")
		(6 "In2.Cu" signal)
		(8 "In3.Cu" power "In3.GND")
		(10 "In4.Cu" power "In4.VCC")
		(12 "In5.Cu" signal)
		(14 "In6.Cu" power "In6.VCC")
		(2 "B.Cu" signal)
		(9 "F.Adhes" user "F.Adhesive")
		(11 "B.Adhes" user "B.Adhesive")
		(13 "F.Paste" user)
		(15 "B.Paste" user)
		(5 "F.SilkS" user "F.Silkscreen")
		(7 "B.SilkS" user "B.Silkscreen")
		(1 "F.Mask" user)
		(3 "B.Mask" user)
		(17 "Dwgs.User" user "User.Drawings")
		(19 "Cmts.User" user "User.Comments")
		(21 "Eco1.User" user "User.Eco1")
		(23 "Eco2.User" user "User.Eco2")
		(25 "Edge.Cuts" user)
		(27 "Margin" user)
		(31 "F.CrtYd" user "F.Courtyard")
		(29 "B.CrtYd" user "B.Courtyard")
		(35 "F.Fab" user)
		(33 "B.Fab" user)
	)
	(footprint "antmicro-footprints:L_1210_3225Metric"
		(layer "F.Cu")
		(at 131.55 55.85 90)
		(property "Reference" "L8"
			(at 2.25 -0.65 180)
			(layer "F.SilkS")
			(effects
				(font
					(size 0.7 0.7)
					(thickness 0.15)
				)
				(justify left bottom)
			)
		)
		(property "Value" "L_680n_6.1A_1210"
			(at 0 2.4 90)
			(layer "F.Fab")
			(effects
				(font
					(size 0.7 0.7)
					(thickness 0.15)
				)
				(justify left bottom)
			)
		)
		(property "Author" "Antmicro"
			(at 187.4 -75.7 0)
			(layer "F.Fab")
			(hide yes)
			(effects
				(font
					(size 1 1)
					(thickness 0.15)
				)
			)
		)
		(property "IMax" ""
			(at 187.4 -75.7 0)
			(layer "F.Fab")
			(hide yes)
			(effects
				(font
					(size 1 1)
					(thickness 0.15)
				)
			)
		)
		(property "ISat" ""
			(at 187.4 -75.7 0)
			(layer "F.Fab")
			(hide yes)
			(effects
				(font
					(size 1 1)
					(thickness 0.15)
				)
			)
		)
		(property "License" "Apache-2.0"
			(at 187.4 -75.7 0)
			(layer "F.Fab")
			(hide yes)
			(effects
				(font
					(size 1 1)
					(thickness 0.15)
				)
			)
		)
		(property "MPN" "DFE322512F-R68M=P2"
			(at 187.4 -75.7 0)
			(layer "F.Fab")
			(hide yes)
			(effects
				(font
					(size 1 1)
					(thickness 0.15)
				)
			)
		)
		(property "Manufacturer" "Murata"
			(at 187.4 -75.7 0)
			(layer "F.Fab")
			(hide yes)
			(effects
				(font
					(size 1 1)
					(thickness 0.15)
				)
			)
		)
		(property "Size" "3.2x2.5"
			(at 187.4 -75.7 0)
			(layer "F.Fab")
			(hide yes)
			(effects
				(font
					(size 1 1)
					(thickness 0.15)
				)
			)
		)
		(property "Val" "680n/6.1A"
			(at 187.4 -75.7 0)
			(layer "F.Fab")
			(hide yes)
			(effects
				(font
					(size 1 1)
					(thickness 0.15)
				)
			)
		)
		(sheetname "Supply")
		(sheetfile "supply.kicad_sch")
		(attr exclude_from_pos_files exclude_from_bom dnp)
		(fp_line
			(start -0.7 -1.4)
			(end 0.7 -1.4)
			(stroke
				(width 0.15)
				(type solid)
			)
			(layer "F.SilkS")
		)
		(fp_line
			(start -0.7 1.4)
			(end 0.7 1.4)
			(stroke
				(width 0.15)
				(type solid)
			)
			(layer "F.SilkS")
		)
		(fp_rect
			(start -2.1 -1.5)
			(end 2.09 1.5)
			(stroke
				(width 0.05)
				(type solid)
			)
			(fill no)
			(layer "F.CrtYd")
		)
		(fp_line
			(start 1.7 -1.351)
			(end -1.701 -1.351)
			(stroke
				(width 0.15)
				(type solid)
			)
			(layer "F.Fab")
		)
		(fp_line
			(start 1.7 1.35)
			(end 1.7 -1.351)
			(stroke
				(width 0.15)
				(type solid)
			)
			(layer "F.Fab")
		)
		(fp_line
			(start 1.7 1.35)
			(end -1.701 1.35)
			(stroke
				(width 0.15)
				(type solid)
			)
			(layer "F.Fab")
		)
		(fp_line
			(start -1.701 1.35)
			(end -1.701 -1.351)
			(stroke
				(width 0.15)
				(type solid)
			)
			(layer "F.Fab")
		)
		(pad "1" smd rect
			(at -1.439 0 90)
			(size 1.24 2.72)
			(layers "F.Cu" "F.Mask" "F.Paste")
			(net 625 "/Supply/VDD2_SW")
			(pintype "passive")
		)
		(pad "2" smd rect
			(at 1.439 0 90)
			(size 1.24 2.72)
			(layers "F.Cu" "F.Mask" "F.Paste")
			(net 550 "VDD1V1")
			(pintype "passive")
		)
	)
	(footprint "antmicro-footprints:L_WE-MAIA-2512"
		(layer "F.Cu")
		(at 126.1825 96.249 180)
		(property "Reference" "L6"
			(at -1.5 -1.4 180)
			(layer "F.SilkS")
			(effects
				(font
					(size 0.7 0.7)
					(thickness 0.15)
				)
				(justify left bottom)
			)
		)
		(property "Value" "784383240047"
			(at 0 2.3 180)
			(layer "F.Fab")
			(effects
				(font
					(size 0.7 0.7)
					(thickness 0.15)
				)
				(justify left bottom)
			)
		)
		(property "Description" "Power Inductor (SMT), AEC-Q200, 470 nH, 3.4 A, Shielded, 6.25 A, WE-MAIA"
			(at 0 0 180)
			(layer "F.Fab")
			(hide yes)
			(effects
				(font
					(size 1.27 1.27)
					(thickness 0.15)
				)
			)
		)
		(property "Author" "Antmicro"
			(at 252.365 192.498 0)
			(layer "F.Fab")
			(hide yes)
			(effects
				(font
					(size 1 1)
					(thickness 0.15)
				)
			)
		)
		(property "IMax" "3.4 A"
			(at 252.365 192.498 0)
			(layer "F.Fab")
			(hide yes)
			(effects
				(font
					(size 1 1)
					(thickness 0.15)
				)
			)
		)
		(property "ISat" "6.25 A"
			(at 252.365 192.498 0)
			(layer "F.Fab")
			(hide yes)
			(effects
				(font
					(size 1 1)
					(thickness 0.15)
				)
			)
		)
		(property "License" "Apache-2.0"
			(at 252.365 192.498 0)
			(layer "F.Fab")
			(hide yes)
			(effects
				(font
					(size 1 1)
					(thickness 0.15)
				)
			)
		)
		(property "MPN" "784383240047"
			(at 252.365 192.498 0)
			(layer "F.Fab")
			(hide yes)
			(effects
				(font
					(size 1 1)
					(thickness 0.15)
				)
			)
		)
		(property "Manufacturer" "Würth Elektronik"
			(at 252.365 192.498 0)
			(layer "F.Fab")
			(hide yes)
			(effects
				(font
					(size 1 1)
					(thickness 0.15)
				)
			)
		)
		(property "Size" "2x2.5"
			(at 252.365 192.498 0)
			(layer "F.Fab")
			(hide yes)
			(effects
				(font
					(size 1 1)
					(thickness 0.15)
				)
			)
		)
		(property "Val" "470n/3.4A"
			(at 252.365 192.498 0)
			(layer "F.Fab")
			(hide yes)
			(effects
				(font
					(size 1 1)
					(thickness 0.15)
				)
			)
		)
		(sheetname "Supply")
		(sheetfile "supply.kicad_sch")
		(attr smd)
		(fp_line
			(start -0.325 1.125)
			(end 0.325 1.125)
			(stroke
				(width 0.15)
				(type solid)
			)
			(layer "F.SilkS")
		)
		(fp_line
			(start -0.325 -1.125)
			(end 0.325 -1.125)
			(stroke
				(width 0.15)
				(type solid)
			)
			(layer "F.SilkS")
		)
		(fp_rect
			(start -1.65 -1.4)
			(end 1.65 1.4)
			(stroke
				(width 0.05)
				(type solid)
			)
			(fill no)
			(layer "F.CrtYd")
		)
		(fp_rect
			(start -1.25 -1)
			(end 1.25 1)
			(stroke
				(width 0.15)
				(type solid)
			)
			(fill no)
			(layer "F.Fab")
		)
		(pad "1" smd roundrect
			(at -0.975 0 180)
			(size 0.85 2.3)
			(layers "F.Cu" "F.Mask" "F.Paste")
			(roundrect_rratio 0.1)
			(net 582 "/Supply/1V0_SW")
			(pintype "passive")
		)
		(pad "2" smd roundrect
			(at 0.975 0 180)
			(size 0.85 2.3)
			(layers "F.Cu" "F.Mask" "F.Paste")
			(roundrect_rratio 0.1)
			(net 588 "/Supply/1V0_REG")
			(pintype "passive")
		)
	)
	(footprint "antmicro-footprints:C_0603_1608Metric"
		(layer "F.Cu")
		(at 127.425 52.725 90)
		(descr "Capacitor SMD 0603")
		(tags "capacitor 0603")
		(property "Reference" "C190"
			(at 1.025 0.775 90)
			(layer "F.SilkS")
			(effects
				(font
					(size 0.7 0.7)
					(thickness 0.15)
				)
				(justify left bottom)
			)
		)
		(property "Value" "C_10u_0603"
			(at 0 1.6 90)
			(layer "F.Fab")
			(effects
				(font
					(size 0.7 0.7)
					(thickness 0.15)
				)
				(justify left bottom)
			)
		)
		(property "Description" " "
			(at 0 0 90)
			(layer "F.Fab")
			(hide yes)
			(effects
				(font
					(size 1.27 1.27)
					(thickness 0.15)
				)
			)
		)
		(property "Author" "Antmicro"
			(at 180.15 -74.7 0)
			(layer "F.Fab")
			(hide yes)
			(effects
				(font
					(size 1 1)
					(thickness 0.15)
				)
			)
		)
		(property "License" "Apache-2.0"
			(at 180.15 -74.7 0)
			(layer "F.Fab")
			(hide yes)
			(effects
				(font
					(size 1 1)
					(thickness 0.15)
				)
			)
		)
		(property "MPN" "GRM188R61A106KE69D"
			(at 180.15 -74.7 0)
			(layer "F.Fab")
			(hide yes)
			(effects
				(font
					(size 1 1)
					(thickness 0.15)
				)
			)
		)
		(property "Manufacturer" "Murata"
			(at 180.15 -74.7 0)
			(layer "F.Fab")
			(hide yes)
			(effects
				(font
					(size 1 1)
					(thickness 0.15)
				)
			)
		)
		(property "Val" "10u"
			(at 180.15 -74.7 0)
			(layer "F.Fab")
			(hide yes)
			(effects
				(font
					(size 1 1)
					(thickness 0.15)
				)
			)
		)
		(property "Voltage" ""
			(at 180.15 -74.7 0)
			(layer "F.Fab")
			(hide yes)
			(effects
				(font
					(size 1 1)
					(thickness 0.15)
				)
			)
		)
		(sheetname "Supply")
		(sheetfile "supply.kicad_sch")
		(attr exclude_from_pos_files exclude_from_bom dnp)
		(fp_line
			(start -0.3 -0.3)
			(end 0.3 -0.3)
			(stroke
				(width 0.15)
				(type solid)
			)
			(layer "F.SilkS")
		)
		(fp_line
			(start -0.3 0.3)
			(end 0.3 0.3)
			(stroke
				(width 0.15)
				(type solid)
			)
			(layer "F.SilkS")
		)
		(fp_rect
			(start -1.24 -0.7)
			(end 1.24 0.7)
			(stroke
				(width 0.05)
				(type solid)
			)
			(fill no)
			(layer "F.CrtYd")
		)
		(fp_rect
			(start -0.8 -0.4)
			(end 0.8 0.4)
			(stroke
				(width 0.15)
				(type solid)
			)
			(fill no)
			(layer "F.Fab")
		)
		(pad "1" smd roundrect
			(at -0.7 0 90)
			(size 0.6 0.8)
			(layers "F.Cu" "F.Mask" "F.Paste")
			(roundrect_rratio 0.2)
			(net 550 "VDD1V1")
			(pintype "passive")
		)
		(pad "2" smd roundrect
			(at 0.7 0 90)
			(size 0.6 0.8)
			(layers "F.Cu" "F.Mask" "F.Paste")
			(roundrect_rratio 0.2)
			(net 5 "GND")
			(pintype "passive")
		)
	)
	(footprint "antmicro-footprints:R_0402_1005Metric"
		(layer "F.Cu")
		(at 137.1 65.7)
		(descr "Resistor SMD 0402")
		(tags "resistor SMD 0402")
		(property "Reference" "R155"
			(at -0.9 2.3 0)
			(layer "F.SilkS")
			(effects
				(font
					(size 0.7 0.7)
					(thickness 0.15)
				)
				(justify left bottom)
			)
		)
		(property "Value" "R_49R9_0402"
			(at 0 1.4 0)
			(layer "F.Fab")
			(effects
				(font
					(size 0.7 0.7)
					(thickness 0.15)
				)
				(justify left bottom)
			)
		)
		(property "Description" "49R9 resistor in 0402 package with 1% tolerance"
			(at 0 0 0)
			(layer "F.Fab")
			(hide yes)
			(effects
				(font
					(size 1.27 1.27)
					(thickness 0.15)
				)
			)
		)
		(property "Author" "Antmicro"
			(at 0 0 0)
			(layer "F.Fab")
			(hide yes)
			(effects
				(font
					(size 1 1)
					(thickness 0.15)
				)
			)
		)
		(property "License" "Apache-2.0"
			(at 0 0 0)
			(layer "F.Fab")
			(hide yes)
			(effects
				(font
					(size 1 1)
					(thickness 0.15)
				)
			)
		)
		(property "MPN" "CR0402-FX-49R9GLF"
			(at 0 0 0)
			(layer "F.Fab")
			(hide yes)
			(effects
				(font
					(size 1 1)
					(thickness 0.15)
				)
			)
		)
		(property "Manufacturer" "Bourns"
			(at 0 0 0)
			(layer "F.Fab")
			(hide yes)
			(effects
				(font
					(size 1 1)
					(thickness 0.15)
				)
			)
		)
		(property "Tolerance" "1%"
			(at 0 0 0)
			(layer "F.Fab")
			(hide yes)
			(effects
				(font
					(size 1 1)
					(thickness 0.15)
				)
			)
		)
		(property "Val" "49R9"
			(at 0 0 0)
			(layer "F.Fab")
			(hide yes)
			(effects
				(font
					(size 1 1)
					(thickness 0.15)
				)
			)
		)
		(sheetname "Supply")
		(sheetfile "supply.kicad_sch")
		(attr smd)
		(fp_rect
			(start -0.93 -0.47)
			(end 0.93 0.47)
			(stroke
				(width 0.05)
				(type solid)
			)
			(fill no)
			(layer "F.CrtYd")
		)
		(fp_rect
			(start -0.5 -0.25)
			(end 0.5 0.25)
			(stroke
				(width 0.15)
				(type solid)
			)
			(fill no)
			(layer "F.Fab")
		)
		(pad "1" smd roundrect
			(at -0.485 0)
			(size 0.59 0.64)
			(layers "F.Cu" "F.Mask" "F.Paste")
			(roundrect_rratio 0.25)
			(net 635 "/Supply/0V6_FB")
			(pintype "passive")
		)
		(pad "2" smd roundrect
			(at 0.485 0)
			(size 0.59 0.64)
			(layers "F.Cu" "F.Mask" "F.Paste")
			(roundrect_rratio 0.25)
			(net 5 "GND")
			(pintype "passive")
		)
	)
	(footprint "antmicro-footprints:R_0402_1005Metric"
		(layer "F.Cu")
		(at 129.9825 100.549 180)
		(descr "Resistor SMD 0402")
		(tags "resistor SMD 0402")
		(property "Reference" "R125"
			(at -0.7175 -0.451 180)
			(layer "F.SilkS")
			(effects
				(font
					(size 0.7 0.7)
					(thickness 0.15)
				)
				(justify left bottom)
			)
		)
		(property "Value" "R_0R_0402"
			(at 0 1.4 180)
			(layer "F.Fab")
			(effects
				(font
					(size 0.7 0.7)
					(thickness 0.15)
				)
				(justify left bottom)
			)
		)
		(property "Description" "0R resistor in 0402 package with unspecified tolerance"
			(at 0 0 180)
			(layer "F.Fab")
			(hide yes)
			(effects
				(font
					(size 1.27 1.27)
					(thickness 0.15)
				)
			)
		)
		(property "Author" "Antmicro"
			(at 259.965 201.098 0)
			(layer "F.Fab")
			(hide yes)
			(effects
				(font
					(size 1 1)
					(thickness 0.15)
				)
			)
		)
		(property "Current" "1A"
			(at 259.965 201.098 0)
			(layer "F.Fab")
			(hide yes)
			(effects
				(font
					(size 1 1)
					(thickness 0.15)
				)
			)
		)
		(property "License" "Apache-2.0"
			(at 259.965 201.098 0)
			(layer "F.Fab")
			(hide yes)
			(effects
				(font
					(size 1 1)
					(thickness 0.15)
				)
			)
		)
		(property "MPN" "ERJ2GE0R00X"
			(at 259.965 201.098 0)
			(layer "F.Fab")
			(hide yes)
			(effects
				(font
					(size 1 1)
					(thickness 0.15)
				)
			)
		)
		(property "Manufacturer" "Panasonic"
			(at 259.965 201.098 0)
			(layer "F.Fab")
			(hide yes)
			(effects
				(font
					(size 1 1)
					(thickness 0.15)
				)
			)
		)
		(property "Tolerance" ""
			(at 259.965 201.098 0)
			(layer "F.Fab")
			(hide yes)
			(effects
				(font
					(size 1 1)
					(thickness 0.15)
				)
			)
		)
		(property "Val" "0R"
			(at 259.965 201.098 0)
			(layer "F.Fab")
			(hide yes)
			(effects
				(font
					(size 1 1)
					(thickness 0.15)
				)
			)
		)
		(sheetname "Supply")
		(sheetfile "supply.kicad_sch")
		(attr smd)
		(fp_rect
			(start -0.93 -0.47)
			(end 0.93 0.47)
			(stroke
				(width 0.05)
				(type solid)
			)
			(fill no)
			(layer "F.CrtYd")
		)
		(fp_rect
			(start -0.5 -0.25)
			(end 0.5 0.25)
			(stroke
				(width 0.15)
				(type solid)
			)
			(fill no)
			(layer "F.Fab")
		)
		(pad "1" smd roundrect
			(at -0.485 0 180)
			(size 0.59 0.64)
			(layers "F.Cu" "F.Mask" "F.Paste")
			(roundrect_rratio 0.25)
			(net 5 "GND")
			(pintype "passive")
		)
		(pad "2" smd roundrect
			(at 0.485 0 180)
			(size 0.59 0.64)
			(layers "F.Cu" "F.Mask" "F.Paste")
			(roundrect_rratio 0.25)
			(net 612 "/Supply/1V0_MODE")
			(pintype "passive")
		)
	)
	(footprint "antmicro-footprints:R_0402_1005Metric"
		(layer "F.Cu")
		(at 111.362806 89.974 180)
		(descr "Resistor SMD 0402")
		(tags "resistor SMD 0402")
		(property "Reference" "R137"
			(at 3.662806 -0.326 180)
			(layer "F.SilkS")
			(effects
				(font
					(size 0.7 0.7)
					(thickness 0.15)
				)
				(justify left bottom)
			)
		)
		(property "Value" "R_10k_0402"
			(at 0 1.4 180)
			(layer "F.Fab")
			(effects
				(font
					(size 0.7 0.7)
					(thickness 0.15)
				)
				(justify left bottom)
			)
		)
		(property "Description" "10k resistor in 0402 package with 1% tolerance"
			(at 0 0 180)
			(layer "F.Fab")
			(hide yes)
			(effects
				(font
					(size 1.27 1.27)
					(thickness 0.15)
				)
			)
		)
		(property "Author" "Antmicro"
			(at 222.725612 179.948 0)
			(layer "F.Fab")
			(hide yes)
			(effects
				(font
					(size 1 1)
					(thickness 0.15)
				)
			)
		)
		(property "License" "Apache-2.0"
			(at 222.725612 179.948 0)
			(layer "F.Fab")
			(hide yes)
			(effects
				(font
					(size 1 1)
					(thickness 0.15)
				)
			)
		)
		(property "MPN" "CR0402-FX-1002GLF"
			(at 222.725612 179.948 0)
			(layer "F.Fab")
			(hide yes)
			(effects
				(font
					(size 1 1)
					(thickness 0.15)
				)
			)
		)
		(property "Manufacturer" "Bourns"
			(at 222.725612 179.948 0)
			(layer "F.Fab")
			(hide yes)
			(effects
				(font
					(size 1 1)
					(thickness 0.15)
				)
			)
		)
		(property "Tolerance" "1%"
			(at 222.725612 179.948 0)
			(layer "F.Fab")
			(hide yes)
			(effects
				(font
					(size 1 1)
					(thickness 0.15)
				)
			)
		)
		(property "Val" "10k"
			(at 222.725612 179.948 0)
			(layer "F.Fab")
			(hide yes)
			(effects
				(font
					(size 1 1)
					(thickness 0.15)
				)
			)
		)
		(sheetname "Supply")
		(sheetfile "supply.kicad_sch")
		(attr smd)
		(fp_rect
			(start -0.93 -0.47)
			(end 0.93 0.47)
			(stroke
				(width 0.05)
				(type solid)
			)
			(fill no)
			(layer "F.CrtYd")
		)
		(fp_rect
			(start -0.5 -0.25)
			(end 0.5 0.25)
			(stroke
				(width 0.15)
				(type solid)
			)
			(fill no)
			(layer "F.Fab")
		)
		(pad "1" smd roundrect
			(at -0.485 0 180)
			(size 0.59 0.64)
			(layers "F.Cu" "F.Mask" "F.Paste")
			(roundrect_rratio 0.25)
			(net 600 "/Supply/1V8_FB")
			(pintype "passive")
		)
		(pad "2" smd roundrect
			(at 0.485 0 180)
			(size 0.59 0.64)
			(layers "F.Cu" "F.Mask" "F.Paste")
			(roundrect_rratio 0.25)
			(net 5 "GND")
			(pintype "passive")
		)
	)
	(footprint "antmicro-footprints:R_0402_1005Metric"
		(layer "F.Cu")
		(at 140.1825 92.099)
		(descr "Resistor SMD 0402")
		(tags "resistor SMD 0402")
		(property "Reference" "R102"
			(at -3.6825 -0.899 0)
			(layer "F.SilkS")
			(effects
				(font
					(size 0.7 0.7)
					(thickness 0.15)
				)
				(justify left bottom)
			)
		)
		(property "Value" "R_330R_0402"
			(at 0 1.4 0)
			(layer "F.Fab")
			(effects
				(font
					(size 0.7 0.7)
					(thickness 0.15)
				)
				(justify left bottom)
			)
		)
		(property "Description" "330R resistor in 0402 package with 1% tolerance"
			(at 0 0 0)
			(layer "F.Fab")
			(hide yes)
			(effects
				(font
					(size 1.27 1.27)
					(thickness 0.15)
				)
			)
		)
		(property "Author" "Antmicro"
			(at 0 0 0)
			(layer "F.Fab")
			(hide yes)
			(effects
				(font
					(size 1 1)
					(thickness 0.15)
				)
			)
		)
		(property "License" "Apache-2.0"
			(at 0 0 0)
			(layer "F.Fab")
			(hide yes)
			(effects
				(font
					(size 1 1)
					(thickness 0.15)
				)
			)
		)
		(property "MPN" "CR0402-FX-3300GLF"
			(at 0 0 0)
			(layer "F.Fab")
			(hide yes)
			(effects
				(font
					(size 1 1)
					(thickness 0.15)
				)
			)
		)
		(property "Manufacturer" "Bourns"
			(at 0 0 0)
			(layer "F.Fab")
			(hide yes)
			(effects
				(font
					(size 1 1)
					(thickness 0.15)
				)
			)
		)
		(property "Tolerance" "1%"
			(at 0 0 0)
			(layer "F.Fab")
			(hide yes)
			(effects
				(font
					(size 1 1)
					(thickness 0.15)
				)
			)
		)
		(property "Val" "330R"
			(at 0 0 0)
			(layer "F.Fab")
			(hide yes)
			(effects
				(font
					(size 1 1)
					(thickness 0.15)
				)
			)
		)
		(sheetname "Supply")
		(sheetfile "supply.kicad_sch")
		(attr smd)
		(fp_rect
			(start -0.93 -0.47)
			(end 0.93 0.47)
			(stroke
				(width 0.05)
				(type solid)
			)
			(fill no)
			(layer "F.CrtYd")
		)
		(fp_rect
			(start -0.5 -0.25)
			(end 0.5 0.25)
			(stroke
				(width 0.15)
				(type solid)
			)
			(fill no)
			(layer "F.Fab")
		)
		(pad "1" smd roundrect
			(at -0.485 0)
			(size 0.59 0.64)
			(layers "F.Cu" "F.Mask" "F.Paste")
			(roundrect_rratio 0.25)
			(net 555 "Net-(PWR3-Pad2)")
			(pintype "passive")
		)
		(pad "2" smd roundrect
			(at 0.485 0)
			(size 0.59 0.64)
			(layers "F.Cu" "F.Mask" "F.Paste")
			(roundrect_rratio 0.25)
			(net 235 "Net-(Q9-D)")
			(pintype "passive")
		)
	)
)
